#ISCELL
  mstr_misc dns *
  *
#ISCELL
  mstr_symbols intel_corp_bpage *
  *
#ISCELL
  mstr_symbols pvddq_def *
  page219_i1
#CELL
  mstr_discrete ir354xx *
  page219_i106
#CELL
  mstr_discrete ir354xx *
  page219_i107
#CELL
  mstr_discrete res *
  page219_i108
#ISCELL
  mstr_symbols gnd *
  page219_i109
#CELL
  mstr_discrete res *
  page219_i110
#ISCELL
  mstr_symbols gnd *
  page219_i111
#ISCELL
  mstr_symbols p5v_stby *
  page219_i112
#CELL
  dev_discrete cap_a *
  page219_i113
#ISCELL
  mstr_symbols gnd *
  page219_i114
#CELL
  dev_discrete cap_a *
  page219_i116
#ISCELL
  mstr_symbols gnd *
  page219_i117
#CELL
  mstr_discrete cap *
  page219_i119
#ISCELL
  mstr_symbols gnd *
  page219_i120
#ISCELL
  mstr_symbols gnd *
  page219_i122
#CELL
  mstr_discrete cap *
  page219_i124
#ISCELL
  mstr_symbols gnd *
  page219_i125
#ISCELL
  mstr_symbols gnd *
  page219_i128
#CELL
  mstr_discrete cap *
  page219_i137
#CELL
  mstr_discrete cap *
  page219_i138
#CELL
  mstr_discrete res *
  page219_i141
#CELL
  mstr_discrete res *
  page219_i142
#CELL
  mstr_discrete res *
  page219_i147
#CELL
  mstr_discrete res *
  page219_i148
#CELL
  w_hdl sc1u10v2kx-4-gp *
  page219_i151
#CELL
  w_hdl sc1u10v2kx-4-gp *
  page219_i152
#CELL
  w_hdl 1r3f-gp *
  page219_i153
#CELL
  w_hdl 1r3f-gp *
  page219_i154
#CELL
  w_hdl ind-120nh-30-gp *
  page219_i157
#CELL
  w_hdl ind-120nh-30-gp *
  page219_i158
#ISCELL
  mstr_symbols gnd *
  page219_i19
#ISCELL
  mstr_standard offpage *
  page219_i3
#ISCELL
  mstr_standard offpage *
  page219_i33
#ISCELL
  mstr_symbols gnd *
  page219_i35
#ISCELL
  mstr_standard offpage *
  page219_i4
#CELL
  mstr_discrete cap *
  page219_i44
#CELL
  mstr_discrete cap *
  page219_i45
#CELL
  mstr_discrete cap *
  page219_i46
#CELL
  mstr_discrete cap *
  page219_i47
#CELL
  mstr_discrete cap *
  page219_i48
#CELL
  mstr_discrete cap *
  page219_i50
#CELL
  dev_discrete cap_a *
  page219_i51
#CELL
  mstr_discrete cap *
  page219_i54
#ISCELL
  mstr_standard offpage *
  page219_i58
#ISCELL
  mstr_standard offpage *
  page219_i61
#ISCELL
  mstr_standard offpage *
  page219_i62
#ISCELL
  mstr_standard offpage *
  page219_i63
#ISCELL
  mstr_symbols pvddq_def *
  page219_i64
#CELL
  mstr_discrete cap *
  page219_i68
#ISCELL
  mstr_symbols gnd *
  page219_i69
#ISCELL
  mstr_symbols gnd *
  page219_i7
#ISCELL
  mstr_symbols gnd *
  page219_i70
#CELL
  mstr_discrete cap *
  page219_i72
#CELL
  mstr_discrete cap *
  page219_i75
#CELL
  mstr_discrete cap *
  page219_i77
#CELL
  dev_discrete cap_a *
  page219_i78
#CELL
  mstr_discrete cap *
  page219_i79
#CELL
  mstr_discrete cap *
  page219_i80
#CELL
  mstr_discrete cap *
  page219_i81
#ISCELL
  mstr_standard offpage *
  page219_i82
#ISCELL
  mstr_symbols vcc_core *
  page219_i83
#CELL
  mstr_discrete cap *
  page219_i84
#ISCELL
  mstr_symbols gnd *
  page219_i85
#ISCELL
  mstr_symbols vcc_core *
  page219_i86
#CELL
  mstr_discrete cap *
  page219_i87
#ISCELL
  mstr_symbols p5v_stby *
  page219_i89
